# T6G (Grand Teton) — schematic netlist excerpt (pin names and nets, part order shuffled) for the footprints in the layout excerpt that follows; sources: Cadence DE-HDL packaged netlist, KiCad conversion of 04192023_DAF0TMB3IC0_F0TG_MB_C_brd_V02_OCP.brd

PU33  ISL99390FRZTR5935  ISL99390FRZ-TR5935 IC  pkg QFN21_6X5XB  page 220
  VOS  = PVDDCR_CPU1_P1_VOS6
  AGND  = GND
  VCC  = PVDDCR_CPU1_P1_VCC6
  PVCC  = PVDDCR_CPU1_P1_PVCC
  PGND1  = GND
  GL1  = NC_PVDDCR_CPU1_P1_GL1_6
  PGND2  = GND
  SW  = SW_PVDDCR_CPU1_P1_SW6
  VIN1  = SW_P12V_AUX_PVDDCR_CPU1_P1_FLT
  VIN2  = SW_P12V_AUX_PVDDCR_CPU1_P1_FLT
  DNC  = NC_PVDDCR_CPU1_P1_DNC6
  PHASE  = SW_PVDDCR_CPU1_P1_BOOTR6
  BOOT  = SW_PVDDCR_CPU1_P1_BOOT6
  PWM  = PVDDCR_CPU1_P1_PWM6
  EN  = PVDDCR_CPU1_P1_VCC6
  TOUT_FLT  = PVDDCR_CPU1_P1_TEMP0
  LSET  = PVDDCR_CPU1_P1_LSET6
  IOUT  = PVDDCR_CPU1_P1_IMON6
  REFIN  = PVDDCR_CPU1_P1_VCCS
  PGND3  = GND
  GL2  = NC_PVDDCR_CPU1_P1_GL2_6

(kicad_pcb
	(version 20260206)
	(generator "pcbnew")
	(generator_version "10.0")
	(general
		(thickness 1.6)
		(legacy_teardrops no)
	)
	(paper "A4")
	(title_block
		(title "04192023_DAF0TMB3IC0_F0TG_MB_C_brd_V02_OCP.brd")
		(comment 1 "Grand Teton / footprints 2183-2183 of 8354")
	)
	(layers
		(0 "F.Cu" signal "TOP")
		(4 "In1.Cu" signal "GND")
		(6 "In2.Cu" signal "IN1")
		(8 "In3.Cu" signal "GND1")
		(10 "In4.Cu" signal "IN2")
		(12 "In5.Cu" signal "GND2")
		(14 "In6.Cu" signal "IN3")
		(16 "In7.Cu" signal "GND3")
		(18 "In8.Cu" signal "VCC")
		(20 "In9.Cu" signal "VCC1")
		(22 "In10.Cu" signal "GND4")
		(24 "In11.Cu" signal "IN4")
		(26 "In12.Cu" signal "GND5")
		(28 "In13.Cu" signal "IN5")
		(30 "In14.Cu" signal "GND6")
		(32 "In15.Cu" signal "IN6")
		(34 "In16.Cu" signal "GND7")
		(2 "B.Cu" signal "BOTTOM")
		(9 "F.Adhes" user "F.Adhesive")
		(11 "B.Adhes" user "B.Adhesive")
		(13 "F.Paste" user "Package Geometry/Pastemask Top")
		(15 "B.Paste" user "Package Geometry/Pastemask Bottom")
		(5 "F.SilkS" user "Ref Des/Silkscreen Top")
		(7 "B.SilkS" user "Ref Des/Silkscreen Bottom")
		(1 "F.Mask" user "Board Geometry/Soldermask Top")
		(3 "B.Mask" user "Board Geometry/Soldermask Bottom")
		(17 "Dwgs.User" user "User.Drawings")
		(19 "Cmts.User" user "User.Comments")
		(21 "Eco1.User" user "User.Eco1")
		(23 "Eco2.User" user "User.Eco2")
		(25 "Edge.Cuts" user "Board Geometry/Outline")
		(27 "Margin" user)
		(31 "F.CrtYd" user "Package Geometry/Place Bound Top")
		(29 "B.CrtYd" user "Package Geometry/Place Bound Bottom")
		(35 "F.Fab" user "Ref Des/Assembly Top")
		(33 "B.Fab" user "Ref Des/Assembly Bottom")
	)
	(footprint ""
		(layer "F.Cu")
		(at 103.729282 -339.939376)
		(property "Reference" "PU33"
			(at -3.018282 -7.632954 0)
			(unlocked yes)
			(layer "F.SilkS")
			(effects
				(font
					(size 0.7874 0.5842)
					(thickness 0.1524)
				)
				(justify left)
			)
		)
		(property "Value" ""
			(at 0 0 0)
			(layer "F.Fab")
			(effects
				(font
					(size 1.27 1.27)
				)
			)
		)
		(duplicate_pad_numbers_are_jumpers no)
		(fp_line
			(start -2.500122 -2.999994)
			(end -2.24409 -2.999994)
			(stroke
				(width 0.1524)
				(type default)
			)
			(layer "F.SilkS")
		)
		(fp_line
			(start -2.500122 -2.529078)
			(end -2.500122 -2.999994)
			(stroke
				(width 0.1524)
				(type default)
			)
			(layer "F.SilkS")
		)
		(fp_line
			(start -2.500122 0.6604)
			(end -2.500122 0.229108)
			(stroke
				(width 0.1524)
				(type default)
			)
			(layer "F.SilkS")
		)
		(fp_line
			(start -2.500122 2.999994)
			(end -2.500122 2.339594)
			(stroke
				(width 0.1524)
				(type default)
			)
			(layer "F.SilkS")
		)
		(fp_line
			(start -2.2987 2.999994)
			(end -2.500122 2.999994)
			(stroke
				(width 0.1524)
				(type default)
			)
			(layer "F.SilkS")
		)
		(fp_line
			(start 2.31394 -2.999994)
			(end 2.500122 -2.999994)
			(stroke
				(width 0.1524)
				(type default)
			)
			(layer "F.SilkS")
		)
		(fp_line
			(start 2.500122 -2.999994)
			(end 2.500122 -2.44348)
			(stroke
				(width 0.1524)
				(type default)
			)
			(layer "F.SilkS")
		)
		(fp_line
			(start 2.500122 2.339594)
			(end 2.500122 2.999994)
			(stroke
				(width 0.1524)
				(type default)
			)
			(layer "F.SilkS")
		)
		(fp_line
			(start 2.500122 2.999994)
			(end 2.2987 2.999994)
			(stroke
				(width 0.1524)
				(type default)
			)
			(layer "F.SilkS")
		)
		(fp_poly
			(pts
				(xy -2.770124 -2.400046) (xy -3.443732 -2.624582) (xy -2.99466 -3.073654)
			)
			(stroke
				(width 0)
				(type default)
			)
			(fill yes)
			(layer "F.SilkS")
		)
		(fp_line
			(start -2.500122 -2.999994)
			(end 2.500122 -2.999994)
			(stroke
				(width 0.1)
				(type default)
			)
			(layer "F.Fab")
		)
		(fp_line
			(start -2.500122 2.999994)
			(end -2.500122 -2.999994)
			(stroke
				(width 0.1)
				(type default)
			)
			(layer "F.Fab")
		)
		(fp_line
			(start 2.500122 -2.999994)
			(end 2.500122 2.999994)
			(stroke
				(width 0.1)
				(type default)
			)
			(layer "F.Fab")
		)
		(fp_line
			(start 2.500122 2.999994)
			(end -2.500122 2.999994)
			(stroke
				(width 0.1)
				(type default)
			)
			(layer "F.Fab")
		)
		(fp_poly
			(pts
				(xy -4.218432 -2.783078) (xy -4.218432 -1.767078) (xy -3.202432 -2.275078)
			)
			(stroke
				(width 0)
				(type default)
			)
			(fill yes)
			(layer "F.Fab")
		)
		(pad "1" smd rect
			(at -2.400046 -2.275078 90)
			(size 0.2286 0.6096)
			(layers "F.Cu" "F.Mask" "F.Paste")
			(net "PVDDCR_CPU1_P1_VOS6")
		)
		(pad "2" smd rect
			(at -2.400046 -1.82499 90)
			(size 0.2286 0.6096)
			(layers "F.Cu" "F.Mask" "F.Paste")
			(net "GND")
		)
		(pad "3" smd rect
			(at -2.400046 -1.374902 90)
			(size 0.2286 0.6096)
			(layers "F.Cu" "F.Mask" "F.Paste")
			(net "PVDDCR_CPU1_P1_VCC6")
		)
		(pad "4" smd rect
			(at -2.400046 -0.925068 90)
			(size 0.2286 0.6096)
			(layers "F.Cu" "F.Mask" "F.Paste")
			(net "PVDDCR_CPU1_P1_PVCC")
		)
		(pad "5" smd rect
			(at -2.400046 -0.47498 90)
			(size 0.2286 0.6096)
			(layers "F.Cu" "F.Mask" "F.Paste")
			(net "GND")
		)
		(pad "6" smd rect
			(at -2.400046 -0.024892 90)
			(size 0.2286 0.6096)
			(layers "F.Cu" "F.Mask" "F.Paste")
			(net "NC_PVDDCR_CPU1_P1_GL1_6")
		)
		(pad "7_9-20_24" smd circle
			(at 0 1.150112 90)
			(size 0 0)
			(layers "F.Cu" "F.Mask" "F.Paste")
			(net "GND")
		)
		(pad "10_19" smd rect
			(at 0 2.899918 90)
			(size 0.6096 4.318)
			(layers "F.Cu" "F.Mask" "F.Paste")
			(net "SW_PVDDCR_CPU1_P1_SW6")
		)
		(pad "25_29" smd rect
			(at 1.549908 -1.279906 270)
			(size 2.0574 2.3114)
			(layers "F.Cu" "F.Mask" "F.Paste")
			(net "SW_P12V_AUX_PVDDCR_CPU1_P1_FLT")
		)
		(pad "30" smd rect
			(at 2.05994 -2.899918)
			(size 0.2286 0.6096)
			(layers "F.Cu" "F.Mask" "F.Paste")
			(net "SW_P12V_AUX_PVDDCR_CPU1_P1_FLT")
		)
		(pad "31" smd rect
			(at 1.610106 -2.899918)
			(size 0.2286 0.6096)
			(layers "F.Cu" "F.Mask" "F.Paste")
			(net "NC_PVDDCR_CPU1_P1_DNC6")
		)
		(pad "32" smd rect
			(at 1.160018 -2.899918)
			(size 0.2286 0.6096)
			(layers "F.Cu" "F.Mask" "F.Paste")
			(net "SW_PVDDCR_CPU1_P1_BOOTR6")
		)
		(pad "33" smd rect
			(at 0.70993 -2.899918)
			(size 0.2286 0.6096)
			(layers "F.Cu" "F.Mask" "F.Paste")
			(net "SW_PVDDCR_CPU1_P1_BOOT6")
		)
		(pad "34" smd rect
			(at 0.260096 -2.899918)
			(size 0.2286 0.6096)
			(layers "F.Cu" "F.Mask" "F.Paste")
			(net "PVDDCR_CPU1_P1_PWM6")
		)
		(pad "35" smd rect
			(at -0.189992 -2.899918)
			(size 0.2286 0.6096)
			(layers "F.Cu" "F.Mask" "F.Paste")
			(net "PVDDCR_CPU1_P1_VCC6")
		)
		(pad "36" smd rect
			(at -0.64008 -2.899918)
			(size 0.2286 0.6096)
			(layers "F.Cu" "F.Mask" "F.Paste")
			(net "PVDDCR_CPU1_P1_TEMP0")
		)
		(pad "37" smd rect
			(at -1.089914 -2.899918)
			(size 0.2286 0.6096)
			(layers "F.Cu" "F.Mask" "F.Paste")
			(net "PVDDCR_CPU1_P1_LSET6")
		)
		(pad "38" smd rect
			(at -1.540002 -2.899918)
			(size 0.2286 0.6096)
			(layers "F.Cu" "F.Mask" "F.Paste")
			(net "PVDDCR_CPU1_P1_IMON6")
		)
		(pad "39" smd rect
			(at -1.99009 -2.899918)
			(size 0.2286 0.6096)
			(layers "F.Cu" "F.Mask" "F.Paste")
			(net "PVDDCR_CPU1_P1_VCCS")
		)
		(pad "40" smd rect
			(at -0.87503 -1.27508)
			(size 1.7526 1.9558)
			(layers "F.Cu" "F.Mask" "F.Paste")
			(net "GND")
		)
		(pad "41" smd rect
			(at -1.525016 0.249936 270)
			(size 0.3048 0.4572)
			(layers "F.Cu" "F.Mask" "F.Paste")
			(net "NC_PVDDCR_CPU1_P1_GL2_6")
		)
		(zone
			(layer "F.Cu")
			(hatch none 0.5)
			(connect_pads
				(clearance 0)
			)
			(min_thickness 0.25)
			(keepout
				(tracks not_allowed)
				(vias allowed)
				(pads allowed)
				(copperpour not_allowed)
				(footprints allowed)
			)
			(placement
				(enabled no)
				(sheetname "")
			)
			(fill
				(thermal_gap 0.5)
				(thermal_bridge_width 0.5)
				(island_removal_mode 0)
			)
			(polygon
				(pts
					(xy 101.22916 -337.356196) (xy 101.22916 -337.688682) (xy 106.229404 -337.688682) (xy 106.229404 -337.362038)
					(xy 105.939082 -337.362038) (xy 105.939082 -337.395058) (xy 101.519482 -337.395058) (xy 101.519482 -337.356196)
				)
			)
		)
		(zone
			(layer "F.Cu")
			(hatch none 0.5)
			(connect_pads
				(clearance 0)
			)
			(min_thickness 0.25)
			(keepout
				(tracks not_allowed)
				(vias allowed)
				(pads allowed)
				(copperpour not_allowed)
				(footprints allowed)
			)
			(placement
				(enabled no)
				(sheetname "")
			)
			(fill
				(thermal_gap 0.5)
				(thermal_bridge_width 0.5)
				(island_removal_mode 0)
			)
			(polygon
				(pts
					(xy 103.781352 -340.185756) (xy 103.781352 -342.243156) (xy 101.927152 -342.243156) (xy 101.927152 -342.00211)
					(xy 101.684836 -342.00211) (xy 101.684836 -342.483694) (xy 105.512616 -342.483694) (xy 105.512616 -342.298782)
					(xy 104.07269 -342.298782) (xy 104.07269 -340.139782) (xy 106.229404 -340.139782) (xy 106.229404 -339.8901)
					(xy 104.077008 -339.8901)
				)
			)
		)
	)
)
